(kicad_pcb
	(version 20260206)
	(generator "pcbnew")
	(generator_version "10.0")
	(general
		(thickness 1.6)
		(legacy_teardrops no)
	)
	(paper "A4")
	(title_block
		(title "Bryce Canyon_SCC_16316-1_OCP.brd")
		(comment 1 "Bryce Canyon / footprints 504-510 of 1561")
	)
	(layers
		(0 "F.Cu" signal "TOP")
		(4 "In1.Cu" signal "L2GND")
		(6 "In2.Cu" signal "L3")
		(8 "In3.Cu" signal "L4VCC")
		(10 "In4.Cu" signal "L5VCC")
		(12 "In5.Cu" signal "L6")
		(14 "In6.Cu" signal "L7GND")
		(2 "B.Cu" signal "BOTTOM")
		(9 "F.Adhes" user "F.Adhesive")
		(11 "B.Adhes" user "B.Adhesive")
		(13 "F.Paste" user "Package Geometry/Pastemask Top")
		(15 "B.Paste" user "Package Geometry/Pastemask Bottom")
		(5 "F.SilkS" user "Ref Des/Silkscreen Top")
		(7 "B.SilkS" user "Ref Des/Silkscreen Bottom")
		(1 "F.Mask" user "Board Geometry/Soldermask Top")
		(3 "B.Mask" user "Board Geometry/Soldermask Bottom")
		(17 "Dwgs.User" user "User.Drawings")
		(19 "Cmts.User" user "User.Comments")
		(21 "Eco1.User" user "User.Eco1")
		(23 "Eco2.User" user "User.Eco2")
		(25 "Edge.Cuts" user "Board Geometry/Outline")
		(27 "Margin" user)
		(31 "F.CrtYd" user "Package Geometry/Place Bound Top")
		(29 "B.CrtYd" user "Package Geometry/Place Bound Bottom")
		(35 "F.Fab" user "Ref Des/Assembly Top")
		(33 "B.Fab" user "Ref Des/Assembly Bottom")
	)
	(footprint ""
		(layer "F.Cu")
		(at 191.8462 -43.0657 -90)
		(property "Reference" "R183"
			(at 0 0 270)
			(layer "F.SilkS")
			(hide yes)
			(effects
				(font
					(size 1.27 1.27)
				)
			)
		)
		(property "Value" "2K2R2F-GP"
			(at 0.064008 -3.993896 270)
			(unlocked yes)
			(layer "F.Fab")
			(hide yes)
			(effects
				(font
					(size 1.016 1.016)
					(thickness 0.1524)
				)
			)
		)
		(property "Device Type" "R402H16"
			(at 0.064008 -5.517896 270)
			(unlocked yes)
			(layer "F.Fab")
			(hide yes)
			(effects
				(font
					(size 1.016 1.016)
					(thickness 0.1524)
				)
			)
		)
		(duplicate_pad_numbers_are_jumpers no)
		(fp_line
			(start -0.508 -0.9398)
			(end -0.508 0.9398)
			(stroke
				(width 0.1524)
				(type default)
			)
			(layer "F.SilkS")
		)
		(fp_line
			(start 0.508 -0.9398)
			(end -0.508 -0.9398)
			(stroke
				(width 0.1524)
				(type default)
			)
			(layer "F.SilkS")
		)
		(fp_rect
			(start -0.508 0.9398)
			(end 0.508 -0.9398)
			(stroke
				(width 0)
				(type default)
			)
			(fill no)
			(layer "F.CrtYd")
		)
		(fp_rect
			(start -0.508 0.9398)
			(end 0.508 -0.9398)
			(stroke
				(width 0)
				(type default)
			)
			(fill no)
			(layer "F.Fab")
		)
		(pad "1" smd custom
			(at 0 -0.4445 270)
			(size 0.1397 0.1397)
			(layers "F.Cu" "F.Mask" "F.Paste")
			(net "P1V8_C")
			(options
				(clearance outline)
				(anchor circle)
			)
			(primitives
				(gr_poly
					(pts
						(arc
							(start -0.1778 -0.2794)
							(mid -0.249642 -0.249642)
							(end -0.2794 -0.1778)
						)
						(arc
							(start -0.2794 0.1778)
							(mid -0.249642 0.249642)
							(end -0.1778 0.2794)
						)
						(arc
							(start 0.1778 0.2794)
							(mid 0.249642 0.249642)
							(end 0.2794 0.1778)
						)
						(arc
							(start 0.2794 -0.1778)
							(mid 0.249642 -0.249642)
							(end 0.1778 -0.2794)
						)
					)
					(width 0)
					(fill yes)
				)
			)
		)
		(pad "2" smd custom
			(at 0 0.4445 270)
			(size 0.1397 0.1397)
			(layers "F.Cu" "F.Mask" "F.Paste")
			(net "I2C_IOC_1_SCL")
			(options
				(clearance outline)
				(anchor circle)
			)
			(primitives
				(gr_poly
					(pts
						(arc
							(start -0.1778 -0.2794)
							(mid -0.249642 -0.249642)
							(end -0.2794 -0.1778)
						)
						(arc
							(start -0.2794 0.1778)
							(mid -0.249642 0.249642)
							(end -0.1778 0.2794)
						)
						(arc
							(start 0.1778 0.2794)
							(mid 0.249642 0.249642)
							(end 0.2794 0.1778)
						)
						(arc
							(start 0.2794 -0.1778)
							(mid 0.249642 -0.249642)
							(end 0.1778 -0.2794)
						)
					)
					(width 0)
					(fill yes)
				)
			)
		)
	)
	(footprint ""
		(layer "F.Cu")
		(at 16.2814 -47.2694 180)
		(property "Reference" "R11"
			(at 0 0 180)
			(layer "F.SilkS")
			(hide yes)
			(effects
				(font
					(size 1.27 1.27)
				)
			)
		)
		(property "Value" "10R2F-L-GP"
			(at 0.064008 -3.993896 180)
			(unlocked yes)
			(layer "F.Fab")
			(hide yes)
			(effects
				(font
					(size 1.016 1.016)
					(thickness 0.1524)
				)
			)
		)
		(property "Device Type" "R402H14"
			(at 0.064008 -5.517896 180)
			(unlocked yes)
			(layer "F.Fab")
			(hide yes)
			(effects
				(font
					(size 1.016 1.016)
					(thickness 0.1524)
				)
			)
		)
		(duplicate_pad_numbers_are_jumpers no)
		(fp_line
			(start 0.508 -0.9398)
			(end -0.508 -0.9398)
			(stroke
				(width 0.1524)
				(type default)
			)
			(layer "F.SilkS")
		)
		(fp_line
			(start -0.508 -0.9398)
			(end -0.508 0.9398)
			(stroke
				(width 0.1524)
				(type default)
			)
			(layer "F.SilkS")
		)
		(fp_rect
			(start -0.508 0.9398)
			(end 0.508 -0.9398)
			(stroke
				(width 0)
				(type default)
			)
			(fill no)
			(layer "F.CrtYd")
		)
		(fp_rect
			(start -0.508 0.9398)
			(end 0.508 -0.9398)
			(stroke
				(width 0)
				(type default)
			)
			(fill no)
			(layer "F.Fab")
		)
		(pad "1" smd custom
			(at 0 -0.4445 180)
			(size 0.1397 0.1397)
			(layers "F.Cu" "F.Mask" "F.Paste")
			(net "P12V_MAIN")
			(options
				(clearance outline)
				(anchor circle)
			)
			(primitives
				(gr_poly
					(pts
						(arc
							(start -0.1778 -0.2794)
							(mid -0.249642 -0.249642)
							(end -0.2794 -0.1778)
						)
						(arc
							(start -0.2794 0.1778)
							(mid -0.249642 0.249642)
							(end -0.1778 0.2794)
						)
						(arc
							(start 0.1778 0.2794)
							(mid 0.249642 0.249642)
							(end 0.2794 0.1778)
						)
						(arc
							(start 0.2794 -0.1778)
							(mid 0.249642 -0.249642)
							(end 0.1778 -0.2794)
						)
					)
					(width 0)
					(fill yes)
				)
			)
		)
		(pad "2" smd custom
			(at 0 0.4445 180)
			(size 0.1397 0.1397)
			(layers "F.Cu" "F.Mask" "F.Paste")
			(net "MB0_VCC")
			(options
				(clearance outline)
				(anchor circle)
			)
			(primitives
				(gr_poly
					(pts
						(arc
							(start -0.1778 -0.2794)
							(mid -0.249642 -0.249642)
							(end -0.2794 -0.1778)
						)
						(arc
							(start -0.2794 0.1778)
							(mid -0.249642 0.249642)
							(end -0.1778 0.2794)
						)
						(arc
							(start 0.1778 0.2794)
							(mid 0.249642 0.249642)
							(end 0.2794 0.1778)
						)
						(arc
							(start 0.2794 -0.1778)
							(mid 0.249642 -0.249642)
							(end 0.1778 -0.2794)
						)
					)
					(width 0)
					(fill yes)
				)
			)
		)
	)
	(footprint ""
		(layer "F.Cu")
		(at 65.024 -72.6948)
		(property "Reference" "R423"
			(at 0 0 0)
			(layer "F.SilkS")
			(hide yes)
			(effects
				(font
					(size 1.27 1.27)
				)
			)
		)
		(property "Value" "0R2J-2-GP"
			(at 0.064008 -3.993896 0)
			(unlocked yes)
			(layer "F.Fab")
			(hide yes)
			(effects
				(font
					(size 1.016 1.016)
					(thickness 0.1524)
				)
			)
		)
		(property "Device Type" "R402H16"
			(at 0.064008 -5.517896 0)
			(unlocked yes)
			(layer "F.Fab")
			(hide yes)
			(effects
				(font
					(size 1.016 1.016)
					(thickness 0.1524)
				)
			)
		)
		(duplicate_pad_numbers_are_jumpers no)
		(fp_line
			(start -0.508 -0.9398)
			(end -0.508 0.9398)
			(stroke
				(width 0.1524)
				(type default)
			)
			(layer "F.SilkS")
		)
		(fp_line
			(start 0.508 -0.9398)
			(end -0.508 -0.9398)
			(stroke
				(width 0.1524)
				(type default)
			)
			(layer "F.SilkS")
		)
		(fp_rect
			(start -0.508 0.9398)
			(end 0.508 -0.9398)
			(stroke
				(width 0)
				(type default)
			)
			(fill no)
			(layer "F.CrtYd")
		)
		(fp_rect
			(start -0.508 0.9398)
			(end 0.508 -0.9398)
			(stroke
				(width 0)
				(type default)
			)
			(fill no)
			(layer "F.Fab")
		)
		(pad "1" smd custom
			(at 0 -0.4445)
			(size 0.1397 0.1397)
			(layers "F.Cu" "F.Mask" "F.Paste")
			(net "LS_EN_U38")
			(options
				(clearance outline)
				(anchor circle)
			)
			(primitives
				(gr_poly
					(pts
						(arc
							(start -0.1778 -0.2794)
							(mid -0.249642 -0.249642)
							(end -0.2794 -0.1778)
						)
						(arc
							(start -0.2794 0.1778)
							(mid -0.249642 0.249642)
							(end -0.1778 0.2794)
						)
						(arc
							(start 0.1778 0.2794)
							(mid 0.249642 0.249642)
							(end 0.2794 0.1778)
						)
						(arc
							(start 0.2794 -0.1778)
							(mid 0.249642 -0.249642)
							(end 0.1778 -0.2794)
						)
					)
					(width 0)
					(fill yes)
				)
			)
		)
		(pad "2" smd custom
			(at 0 0.4445)
			(size 0.1397 0.1397)
			(layers "F.Cu" "F.Mask" "F.Paste")
			(net "VREF5")
			(options
				(clearance outline)
				(anchor circle)
			)
			(primitives
				(gr_poly
					(pts
						(arc
							(start -0.1778 -0.2794)
							(mid -0.249642 -0.249642)
							(end -0.2794 -0.1778)
						)
						(arc
							(start -0.2794 0.1778)
							(mid -0.249642 0.249642)
							(end -0.1778 0.2794)
						)
						(arc
							(start 0.1778 0.2794)
							(mid 0.249642 0.249642)
							(end 0.2794 0.1778)
						)
						(arc
							(start 0.2794 -0.1778)
							(mid 0.249642 -0.249642)
							(end 0.1778 -0.2794)
						)
					)
					(width 0)
					(fill yes)
				)
			)
		)
	)
	(footprint ""
		(layer "F.Cu")
		(at 142.24 -100.584)
		(property "Reference" "L35"
			(at 0 0 0)
			(layer "F.SilkS")
			(hide yes)
			(effects
				(font
					(size 1.27 1.27)
				)
			)
		)
		(property "Value" "MPZ2012S300AT-GP"
			(at 0 -4.2418 0)
			(unlocked yes)
			(layer "F.Fab")
			(hide yes)
			(effects
				(font
					(size 1.016 1.016)
					(thickness 0.1524)
				)
			)
		)
		(property "Device Type" "L805H42"
			(at 0 -5.7912 0)
			(unlocked yes)
			(layer "F.Fab")
			(hide yes)
			(effects
				(font
					(size 1.016 1.016)
					(thickness 0.1524)
				)
			)
		)
		(duplicate_pad_numbers_are_jumpers no)
		(fp_line
			(start -0.889 -1.7018)
			(end 0.889 -1.7018)
			(stroke
				(width 0.1524)
				(type default)
			)
			(layer "F.SilkS")
		)
		(fp_line
			(start -0.889 1.7018)
			(end -0.889 -1.7018)
			(stroke
				(width 0.1524)
				(type default)
			)
			(layer "F.SilkS")
		)
		(fp_line
			(start 0.889 -1.7018)
			(end 0.889 1.7018)
			(stroke
				(width 0.1524)
				(type default)
			)
			(layer "F.SilkS")
		)
		(fp_line
			(start 0.889 1.7018)
			(end -0.889 1.7018)
			(stroke
				(width 0.1524)
				(type default)
			)
			(layer "F.SilkS")
		)
		(fp_rect
			(start -0.9652 1.778)
			(end 0.9652 -1.778)
			(stroke
				(width 0)
				(type default)
			)
			(fill no)
			(layer "F.CrtYd")
		)
		(fp_rect
			(start -0.9652 1.778)
			(end 0.9652 -1.778)
			(stroke
				(width 0)
				(type default)
			)
			(fill no)
			(layer "F.Fab")
		)
		(pad "1" smd rect
			(at 0 -0.9652)
			(size 1.397 1.143)
			(layers "F.Cu" "F.Mask" "F.Paste")
			(net "P1V5_E")
		)
		(pad "2" smd rect
			(at 0 0.9652)
			(size 1.397 1.143)
			(layers "F.Cu" "F.Mask" "F.Paste")
			(net "GB_VDDH")
		)
	)
	(footprint ""
		(layer "F.Cu")
		(at 54.0512 -77.4954 180)
		(property "Reference" "U41"
			(at 0 0 180)
			(layer "F.SilkS")
			(hide yes)
			(effects
				(font
					(size 1.27 1.27)
				)
			)
		)
		(property "Value" "PCA9306DCTR-GP"
			(at 0 -11.6332 180)
			(unlocked yes)
			(layer "F.Fab")
			(hide yes)
			(effects
				(font
					(size 1.016 1.016)
					(thickness 0.1524)
				)
			)
		)
		(property "Device Type" "SSOIC8H52"
			(at 0 -13.1572 180)
			(unlocked yes)
			(layer "F.Fab")
			(hide yes)
			(effects
				(font
					(size 1.016 1.016)
					(thickness 0.1524)
				)
			)
		)
		(duplicate_pad_numbers_are_jumpers no)
		(fp_line
			(start 1.0668 0.5842)
			(end -1.524 0.5842)
			(stroke
				(width 0.1524)
				(type default)
			)
			(layer "F.SilkS")
		)
		(fp_line
			(start 1.0668 -0.5842)
			(end 1.0668 0.5842)
			(stroke
				(width 0.1524)
				(type default)
			)
			(layer "F.SilkS")
		)
		(fp_line
			(start -1.397 0)
			(end -1.7018 0.3048)
			(stroke
				(width 0.1524)
				(type default)
			)
			(layer "F.SilkS")
		)
		(fp_line
			(start -1.397 0)
			(end -1.7018 -0.3048)
			(stroke
				(width 0.1524)
				(type default)
			)
			(layer "F.SilkS")
		)
		(fp_line
			(start -1.524 0.5842)
			(end -1.524 2.286)
			(stroke
				(width 0.508)
				(type default)
			)
			(layer "F.SilkS")
		)
		(fp_line
			(start -1.7018 -0.5842)
			(end 1.0668 -0.5842)
			(stroke
				(width 0.1524)
				(type default)
			)
			(layer "F.SilkS")
		)
		(fp_line
			(start -1.7018 -0.5842)
			(end -1.7018 2.286)
			(stroke
				(width 0.1524)
				(type default)
			)
			(layer "F.SilkS")
		)
		(fp_poly
			(pts
				(xy -1.1684 -0.5842) (xy 1.0668 -0.5842) (xy 1.0668 0.5842) (xy -1.1684 0.5842)
			)
			(stroke
				(width 0)
				(type default)
			)
			(fill yes)
			(layer "F.SilkS")
		)
		(fp_poly
			(pts
				(xy -1.778 2.54) (xy 1.778 2.54) (xy 1.778 -2.54) (xy -1.778 -2.54)
			)
			(stroke
				(width 0)
				(type default)
			)
			(fill no)
			(layer "F.CrtYd")
		)
		(fp_poly
			(pts
				(xy -1.778 -2.54) (xy 1.778 -2.54) (xy 1.778 2.54) (xy -1.778 2.54)
			)
			(stroke
				(width 0)
				(type default)
			)
			(fill no)
			(layer "F.Fab")
		)
		(pad "1" smd rect
			(at -0.97536 1.6256 180)
			(size 0.3556 1.524)
			(layers "F.Cu" "F.Mask" "F.Paste")
			(net "GND")
		)
		(pad "2" smd rect
			(at -0.32512 1.6256 180)
			(size 0.3556 1.524)
			(layers "F.Cu" "F.Mask" "F.Paste")
			(net "P1V8_E")
		)
		(pad "3" smd rect
			(at 0.32512 1.6256 180)
			(size 0.3556 1.524)
			(layers "F.Cu" "F.Mask" "F.Paste")
			(net "I2C_CLIP_SCL7_LS")
		)
		(pad "4" smd rect
			(at 0.97536 1.6256 180)
			(size 0.3556 1.524)
			(layers "F.Cu" "F.Mask" "F.Paste")
			(net "I2C_CLIP_SDA7_LS")
		)
		(pad "5" smd rect
			(at 0.97536 -1.6256 180)
			(size 0.3556 1.524)
			(layers "F.Cu" "F.Mask" "F.Paste")
			(net "I2C_CLIP_SDA7")
		)
		(pad "6" smd rect
			(at 0.32512 -1.6256 180)
			(size 0.3556 1.524)
			(layers "F.Cu" "F.Mask" "F.Paste")
			(net "I2C_CLIP_SCL7")
		)
		(pad "7" smd rect
			(at -0.32512 -1.6256 180)
			(size 0.3556 1.524)
			(layers "F.Cu" "F.Mask" "F.Paste")
			(net "VREF7")
		)
		(pad "8" smd rect
			(at -0.97536 -1.6256 180)
			(size 0.3556 1.524)
			(layers "F.Cu" "F.Mask" "F.Paste")
			(net "LS_EN_U41")
		)
	)
	(footprint ""
		(layer "F.Cu")
		(at 136.398 -107.6706 -90)
		(property "Reference" "C695"
			(at 0 0 270)
			(layer "F.SilkS")
			(hide yes)
			(effects
				(font
					(size 1.27 1.27)
				)
			)
		)
		(property "Value" "SC10U6D3V5KX-4GP"
			(at -0.0762 -6.1214 270)
			(unlocked yes)
			(layer "F.Fab")
			(hide yes)
			(effects
				(font
					(size 1.016 1.016)
					(thickness 0.1524)
				)
			)
		)
		(property "Device Type" "C805H58"
			(at -0.0762 -8.1534 270)
			(unlocked yes)
			(layer "F.Fab")
			(hide yes)
			(effects
				(font
					(size 1.016 1.016)
					(thickness 0.1524)
				)
			)
		)
		(duplicate_pad_numbers_are_jumpers no)
		(fp_line
			(start 0.635 0)
			(end -0.635 0)
			(stroke
				(width 0.508)
				(type default)
			)
			(layer "F.SilkS")
		)
		(fp_rect
			(start -0.9652 1.778)
			(end 0.9652 -1.778)
			(stroke
				(width 0)
				(type default)
			)
			(fill no)
			(layer "F.CrtYd")
		)
		(fp_poly
			(pts
				(xy -0.9652 -1.778) (xy 0.9652 -1.778) (xy 0.9652 1.778) (xy -0.9652 1.778)
			)
			(stroke
				(width 0)
				(type default)
			)
			(fill no)
			(layer "F.Fab")
		)
		(pad "1" smd rect
			(at 0 -0.9652 270)
			(size 1.397 1.143)
			(layers "F.Cu" "F.Mask" "F.Paste")
			(net "P1V5_E_OUT")
		)
		(pad "2" smd rect
			(at 0 0.9652 270)
			(size 1.397 1.143)
			(layers "F.Cu" "F.Mask" "F.Paste")
			(net "GND")
		)
	)
	(footprint ""
		(layer "F.Cu")
		(at 187.27928 -108.70692 -90)
		(property "Reference" "C715"
			(at 0 0 270)
			(layer "F.SilkS")
			(hide yes)
			(effects
				(font
					(size 1.27 1.27)
				)
			)
		)
		(property "Value" "SCD1U16V2KX-3GP"
			(at 1.1811 -2.7051 270)
			(unlocked yes)
			(layer "F.Fab")
			(hide yes)
			(effects
				(font
					(size 1.016 1.016)
					(thickness 0.1524)
				)
			)
		)
		(property "Device Type" "C402H22"
			(at 1.1811 -4.2291 270)
			(unlocked yes)
			(layer "F.Fab")
			(hide yes)
			(effects
				(font
					(size 1.016 1.016)
					(thickness 0.1524)
				)
			)
		)
		(duplicate_pad_numbers_are_jumpers no)
		(fp_rect
			(start -0.4318 0.9525)
			(end 0.4318 -0.9525)
			(stroke
				(width 0)
				(type default)
			)
			(fill no)
			(layer "F.CrtYd")
		)
		(fp_rect
			(start -0.4318 0.9525)
			(end 0.4318 -0.9525)
			(stroke
				(width 0)
				(type default)
			)
			(fill no)
			(layer "F.Fab")
		)
		(pad "1" smd custom
			(at 0 -0.4445 270)
			(size 0.1524 0.1524)
			(layers "F.Cu" "F.Mask" "F.Paste")
			(net "P1V8_C_S")
			(options
				(clearance outline)
				(anchor circle)
			)
			(primitives
				(gr_poly
					(pts
						(arc
							(start 0.3048 -0.2032)
							(mid 0.275042 -0.275042)
							(end 0.2032 -0.3048)
						)
						(arc
							(start -0.2032 -0.3048)
							(mid -0.275042 -0.275042)
							(end -0.3048 -0.2032)
						)
						(arc
							(start -0.3048 0.2032)
							(mid -0.275042 0.275042)
							(end -0.2032 0.3048)
						)
						(arc
							(start 0.2032 0.3048)
							(mid 0.275042 0.275042)
							(end 0.3048 0.2032)
						)
					)
					(width 0)
					(fill yes)
				)
			)
		)
		(pad "2" smd custom
			(at 0 0.4445 270)
			(size 0.1524 0.1524)
			(layers "F.Cu" "F.Mask" "F.Paste")
			(net "GND")
			(options
				(clearance outline)
				(anchor circle)
			)
			(primitives
				(gr_poly
					(pts
						(arc
							(start 0.3048 -0.2032)
							(mid 0.275042 -0.275042)
							(end 0.2032 -0.3048)
						)
						(arc
							(start -0.2032 -0.3048)
							(mid -0.275042 -0.275042)
							(end -0.3048 -0.2032)
						)
						(arc
							(start -0.3048 0.2032)
							(mid -0.275042 0.275042)
							(end -0.2032 0.3048)
						)
						(arc
							(start 0.2032 0.3048)
							(mid 0.275042 0.275042)
							(end 0.3048 0.2032)
						)
					)
					(width 0)
					(fill yes)
				)
			)
		)
	)
)
